(kicad_pcb
	(version 20260206)
	(generator "pcbnew")
	(generator_version "10.0")
	(general
		(thickness 1.6)
		(legacy_teardrops no)
	)
	(paper "A4")
	(title_block
		(title "Bryce Canyon_IOM_M2_16342-2_OCP.brd")
		(comment 1 "Bryce Canyon / footprints 149-156 of 1146")
	)
	(layers
		(0 "F.Cu" signal "TOP")
		(4 "In1.Cu" signal "L2GND")
		(6 "In2.Cu" signal "L3")
		(8 "In3.Cu" signal "L4VCC")
		(10 "In4.Cu" signal "L5VCC")
		(12 "In5.Cu" signal "L6")
		(14 "In6.Cu" signal "L7GND")
		(2 "B.Cu" signal "BOTTOM")
		(9 "F.Adhes" user "F.Adhesive")
		(11 "B.Adhes" user "B.Adhesive")
		(13 "F.Paste" user "Package Geometry/Pastemask Top")
		(15 "B.Paste" user "Package Geometry/Pastemask Bottom")
		(5 "F.SilkS" user "Ref Des/Silkscreen Top")
		(7 "B.SilkS" user "Ref Des/Silkscreen Bottom")
		(1 "F.Mask" user "Board Geometry/Soldermask Top")
		(3 "B.Mask" user "Board Geometry/Soldermask Bottom")
		(17 "Dwgs.User" user "User.Drawings")
		(19 "Cmts.User" user "User.Comments")
		(21 "Eco1.User" user "User.Eco1")
		(23 "Eco2.User" user "User.Eco2")
		(25 "Edge.Cuts" user "Board Geometry/Outline")
		(27 "Margin" user)
		(31 "F.CrtYd" user "Package Geometry/Place Bound Top")
		(29 "B.CrtYd" user "Package Geometry/Place Bound Bottom")
		(35 "F.Fab" user "Ref Des/Assembly Top")
		(33 "B.Fab" user "Ref Des/Assembly Bottom")
	)
	(footprint ""
		(layer "F.Cu")
		(at 43.623738 -179.49545)
		(property "Reference" "C181"
			(at 0 0 0)
			(layer "F.SilkS")
			(hide yes)
			(effects
				(font
					(size 1.27 1.27)
				)
			)
		)
		(property "Value" "SCD1U25V2KX-2-GP"
			(at 1.1811 -2.7051 0)
			(unlocked yes)
			(layer "F.Fab")
			(hide yes)
			(effects
				(font
					(size 1.016 1.016)
					(thickness 0.1524)
				)
			)
		)
		(property "Device Type" "C402H22"
			(at 1.1811 -4.2291 0)
			(unlocked yes)
			(layer "F.Fab")
			(hide yes)
			(effects
				(font
					(size 1.016 1.016)
					(thickness 0.1524)
				)
			)
		)
		(duplicate_pad_numbers_are_jumpers no)
		(fp_rect
			(start -0.4318 0.9525)
			(end 0.4318 -0.9525)
			(stroke
				(width 0)
				(type default)
			)
			(fill no)
			(layer "F.CrtYd")
		)
		(fp_rect
			(start -0.4318 0.9525)
			(end 0.4318 -0.9525)
			(stroke
				(width 0)
				(type default)
			)
			(fill no)
			(layer "F.Fab")
		)
		(pad "1" smd custom
			(at 0 -0.4445)
			(size 0.1524 0.1524)
			(layers "F.Cu" "F.Mask" "F.Paste")
			(net "P3V3_STBY_OUT")
			(options
				(clearance outline)
				(anchor circle)
			)
			(primitives
				(gr_poly
					(pts
						(arc
							(start 0.3048 -0.2032)
							(mid 0.275042 -0.275042)
							(end 0.2032 -0.3048)
						)
						(arc
							(start -0.2032 -0.3048)
							(mid -0.275042 -0.275042)
							(end -0.3048 -0.2032)
						)
						(arc
							(start -0.3048 0.2032)
							(mid -0.275042 0.275042)
							(end -0.2032 0.3048)
						)
						(arc
							(start 0.2032 0.3048)
							(mid 0.275042 0.275042)
							(end 0.3048 0.2032)
						)
					)
					(width 0)
					(fill yes)
				)
			)
		)
		(pad "2" smd custom
			(at 0 0.4445)
			(size 0.1524 0.1524)
			(layers "F.Cu" "F.Mask" "F.Paste")
			(net "P3V3_STBY_LL_R")
			(options
				(clearance outline)
				(anchor circle)
			)
			(primitives
				(gr_poly
					(pts
						(arc
							(start 0.3048 -0.2032)
							(mid 0.275042 -0.275042)
							(end 0.2032 -0.3048)
						)
						(arc
							(start -0.2032 -0.3048)
							(mid -0.275042 -0.275042)
							(end -0.3048 -0.2032)
						)
						(arc
							(start -0.3048 0.2032)
							(mid -0.275042 0.275042)
							(end -0.2032 0.3048)
						)
						(arc
							(start 0.2032 0.3048)
							(mid 0.275042 0.275042)
							(end 0.3048 0.2032)
						)
					)
					(width 0)
					(fill yes)
				)
			)
		)
	)
	(footprint ""
		(layer "F.Cu")
		(at 32.6898 -135.7884 90)
		(property "Reference" "R283"
			(at 0 0 90)
			(layer "F.SilkS")
			(hide yes)
			(effects
				(font
					(size 1.27 1.27)
				)
			)
		)
		(property "Value" "33R2F-3-GP"
			(at 0.064008 -3.993896 90)
			(unlocked yes)
			(layer "F.Fab")
			(hide yes)
			(effects
				(font
					(size 1.016 1.016)
					(thickness 0.1524)
				)
			)
		)
		(property "Device Type" "R402H16"
			(at 0.064008 -5.517896 90)
			(unlocked yes)
			(layer "F.Fab")
			(hide yes)
			(effects
				(font
					(size 1.016 1.016)
					(thickness 0.1524)
				)
			)
		)
		(duplicate_pad_numbers_are_jumpers no)
		(fp_line
			(start 0.508 -0.9398)
			(end -0.508 -0.9398)
			(stroke
				(width 0.1524)
				(type default)
			)
			(layer "F.SilkS")
		)
		(fp_line
			(start -0.508 -0.9398)
			(end -0.508 0.9398)
			(stroke
				(width 0.1524)
				(type default)
			)
			(layer "F.SilkS")
		)
		(fp_rect
			(start -0.508 0.9398)
			(end 0.508 -0.9398)
			(stroke
				(width 0)
				(type default)
			)
			(fill no)
			(layer "F.CrtYd")
		)
		(fp_rect
			(start -0.508 0.9398)
			(end 0.508 -0.9398)
			(stroke
				(width 0)
				(type default)
			)
			(fill no)
			(layer "F.Fab")
		)
		(pad "1" smd custom
			(at 0 -0.4445 90)
			(size 0.1397 0.1397)
			(layers "F.Cu" "F.Mask" "F.Paste")
			(net "BMC_SPI_CLK_R")
			(options
				(clearance outline)
				(anchor circle)
			)
			(primitives
				(gr_poly
					(pts
						(arc
							(start -0.1778 -0.2794)
							(mid -0.249642 -0.249642)
							(end -0.2794 -0.1778)
						)
						(arc
							(start -0.2794 0.1778)
							(mid -0.249642 0.249642)
							(end -0.1778 0.2794)
						)
						(arc
							(start 0.1778 0.2794)
							(mid 0.249642 0.249642)
							(end 0.2794 0.1778)
						)
						(arc
							(start 0.2794 -0.1778)
							(mid 0.249642 -0.249642)
							(end 0.1778 -0.2794)
						)
					)
					(width 0)
					(fill yes)
				)
			)
		)
		(pad "2" smd custom
			(at 0 0.4445 90)
			(size 0.1397 0.1397)
			(layers "F.Cu" "F.Mask" "F.Paste")
			(net "BMC_SPI_CLK")
			(options
				(clearance outline)
				(anchor circle)
			)
			(primitives
				(gr_poly
					(pts
						(arc
							(start -0.1778 -0.2794)
							(mid -0.249642 -0.249642)
							(end -0.2794 -0.1778)
						)
						(arc
							(start -0.2794 0.1778)
							(mid -0.249642 0.249642)
							(end -0.1778 0.2794)
						)
						(arc
							(start 0.1778 0.2794)
							(mid 0.249642 0.249642)
							(end 0.2794 0.1778)
						)
						(arc
							(start 0.2794 -0.1778)
							(mid 0.249642 -0.249642)
							(end 0.1778 -0.2794)
						)
					)
					(width 0)
					(fill yes)
				)
			)
		)
	)
	(footprint ""
		(layer "F.Cu")
		(at 66.71183 -179.45989 180)
		(property "Reference" "R82"
			(at 0 0 180)
			(layer "F.SilkS")
			(hide yes)
			(effects
				(font
					(size 1.27 1.27)
				)
			)
		)
		(property "Value" "10KR2F-2-GP"
			(at 0.064008 -3.993896 180)
			(unlocked yes)
			(layer "F.Fab")
			(hide yes)
			(effects
				(font
					(size 1.016 1.016)
					(thickness 0.1524)
				)
			)
		)
		(property "Device Type" "R402H16"
			(at 0.064008 -5.517896 180)
			(unlocked yes)
			(layer "F.Fab")
			(hide yes)
			(effects
				(font
					(size 1.016 1.016)
					(thickness 0.1524)
				)
			)
		)
		(duplicate_pad_numbers_are_jumpers no)
		(fp_line
			(start 0.508 -0.9398)
			(end -0.508 -0.9398)
			(stroke
				(width 0.1524)
				(type default)
			)
			(layer "F.SilkS")
		)
		(fp_line
			(start -0.508 -0.9398)
			(end -0.508 0.9398)
			(stroke
				(width 0.1524)
				(type default)
			)
			(layer "F.SilkS")
		)
		(fp_rect
			(start -0.508 0.9398)
			(end 0.508 -0.9398)
			(stroke
				(width 0)
				(type default)
			)
			(fill no)
			(layer "F.CrtYd")
		)
		(fp_rect
			(start -0.508 0.9398)
			(end 0.508 -0.9398)
			(stroke
				(width 0)
				(type default)
			)
			(fill no)
			(layer "F.Fab")
		)
		(pad "1" smd custom
			(at 0 -0.4445 180)
			(size 0.1397 0.1397)
			(layers "F.Cu" "F.Mask" "F.Paste")
			(net "VREF_2V2")
			(options
				(clearance outline)
				(anchor circle)
			)
			(primitives
				(gr_poly
					(pts
						(arc
							(start -0.1778 -0.2794)
							(mid -0.249642 -0.249642)
							(end -0.2794 -0.1778)
						)
						(arc
							(start -0.2794 0.1778)
							(mid -0.249642 0.249642)
							(end -0.1778 0.2794)
						)
						(arc
							(start 0.1778 0.2794)
							(mid 0.249642 0.249642)
							(end 0.2794 0.1778)
						)
						(arc
							(start 0.2794 -0.1778)
							(mid 0.249642 -0.249642)
							(end 0.1778 -0.2794)
						)
					)
					(width 0)
					(fill yes)
				)
			)
		)
		(pad "2" smd custom
			(at 0 0.4445 180)
			(size 0.1397 0.1397)
			(layers "F.Cu" "F.Mask" "F.Paste")
			(net "GND")
			(options
				(clearance outline)
				(anchor circle)
			)
			(primitives
				(gr_poly
					(pts
						(arc
							(start -0.1778 -0.2794)
							(mid -0.249642 -0.249642)
							(end -0.2794 -0.1778)
						)
						(arc
							(start -0.2794 0.1778)
							(mid -0.249642 0.249642)
							(end -0.1778 0.2794)
						)
						(arc
							(start 0.1778 0.2794)
							(mid 0.249642 0.249642)
							(end 0.2794 0.1778)
						)
						(arc
							(start 0.2794 -0.1778)
							(mid 0.249642 -0.249642)
							(end 0.1778 -0.2794)
						)
					)
					(width 0)
					(fill yes)
				)
			)
		)
	)
	(footprint ""
		(layer "F.Cu")
		(at 82.94116 -155.321 90)
		(property "Reference" "C236"
			(at 0 0 90)
			(layer "F.SilkS")
			(hide yes)
			(effects
				(font
					(size 1.27 1.27)
				)
			)
		)
		(property "Value" "SC10U6D3V5KX-4GP"
			(at -0.0762 -6.1214 90)
			(unlocked yes)
			(layer "F.Fab")
			(hide yes)
			(effects
				(font
					(size 1.016 1.016)
					(thickness 0.1524)
				)
			)
		)
		(property "Device Type" "C805H58"
			(at -0.0762 -8.1534 90)
			(unlocked yes)
			(layer "F.Fab")
			(hide yes)
			(effects
				(font
					(size 1.016 1.016)
					(thickness 0.1524)
				)
			)
		)
		(duplicate_pad_numbers_are_jumpers no)
		(fp_line
			(start 0.635 0)
			(end -0.635 0)
			(stroke
				(width 0.508)
				(type default)
			)
			(layer "F.SilkS")
		)
		(fp_rect
			(start -0.9652 1.778)
			(end 0.9652 -1.778)
			(stroke
				(width 0)
				(type default)
			)
			(fill no)
			(layer "F.CrtYd")
		)
		(fp_poly
			(pts
				(xy -0.9652 -1.778) (xy 0.9652 -1.778) (xy 0.9652 1.778) (xy -0.9652 1.778)
			)
			(stroke
				(width 0)
				(type default)
			)
			(fill no)
			(layer "F.Fab")
		)
		(pad "1" smd rect
			(at 0 -0.9652 90)
			(size 1.397 1.143)
			(layers "F.Cu" "F.Mask" "F.Paste")
			(net "TPS74801_P1V15_STBY_OUT")
		)
		(pad "2" smd rect
			(at 0 0.9652 90)
			(size 1.397 1.143)
			(layers "F.Cu" "F.Mask" "F.Paste")
			(net "GND")
		)
	)
	(footprint ""
		(layer "F.Cu")
		(at 27.419046 -155.464256 -90)
		(property "Reference" "R772"
			(at 0 0 270)
			(layer "F.SilkS")
			(hide yes)
			(effects
				(font
					(size 1.27 1.27)
				)
			)
		)
		(property "Value" "0R2J-2-GP"
			(at 0.064008 -3.993896 270)
			(unlocked yes)
			(layer "F.Fab")
			(hide yes)
			(effects
				(font
					(size 1.016 1.016)
					(thickness 0.1524)
				)
			)
		)
		(property "Device Type" "R402H16"
			(at 0.064008 -5.517896 270)
			(unlocked yes)
			(layer "F.Fab")
			(hide yes)
			(effects
				(font
					(size 1.016 1.016)
					(thickness 0.1524)
				)
			)
		)
		(duplicate_pad_numbers_are_jumpers no)
		(fp_line
			(start -0.508 -0.9398)
			(end -0.508 0.9398)
			(stroke
				(width 0.1524)
				(type default)
			)
			(layer "F.SilkS")
		)
		(fp_line
			(start 0.508 -0.9398)
			(end -0.508 -0.9398)
			(stroke
				(width 0.1524)
				(type default)
			)
			(layer "F.SilkS")
		)
		(fp_rect
			(start -0.508 0.9398)
			(end 0.508 -0.9398)
			(stroke
				(width 0)
				(type default)
			)
			(fill no)
			(layer "F.CrtYd")
		)
		(fp_rect
			(start -0.508 0.9398)
			(end 0.508 -0.9398)
			(stroke
				(width 0)
				(type default)
			)
			(fill no)
			(layer "F.Fab")
		)
		(pad "1" smd custom
			(at 0 -0.4445 270)
			(size 0.1397 0.1397)
			(layers "F.Cu" "F.Mask" "F.Paste")
			(net "DEBUG_GPIO_BMC_R_5")
			(options
				(clearance outline)
				(anchor circle)
			)
			(primitives
				(gr_poly
					(pts
						(arc
							(start -0.1778 -0.2794)
							(mid -0.249642 -0.249642)
							(end -0.2794 -0.1778)
						)
						(arc
							(start -0.2794 0.1778)
							(mid -0.249642 0.249642)
							(end -0.1778 0.2794)
						)
						(arc
							(start 0.1778 0.2794)
							(mid 0.249642 0.249642)
							(end 0.2794 0.1778)
						)
						(arc
							(start 0.2794 -0.1778)
							(mid 0.249642 -0.249642)
							(end 0.1778 -0.2794)
						)
					)
					(width 0)
					(fill yes)
				)
			)
		)
		(pad "2" smd custom
			(at 0 0.4445 270)
			(size 0.1397 0.1397)
			(layers "F.Cu" "F.Mask" "F.Paste")
			(net "DEBUG_GPIO_BMC_5")
			(options
				(clearance outline)
				(anchor circle)
			)
			(primitives
				(gr_poly
					(pts
						(arc
							(start -0.1778 -0.2794)
							(mid -0.249642 -0.249642)
							(end -0.2794 -0.1778)
						)
						(arc
							(start -0.2794 0.1778)
							(mid -0.249642 0.249642)
							(end -0.1778 0.2794)
						)
						(arc
							(start 0.1778 0.2794)
							(mid 0.249642 0.249642)
							(end 0.2794 0.1778)
						)
						(arc
							(start 0.2794 -0.1778)
							(mid 0.249642 -0.249642)
							(end 0.1778 -0.2794)
						)
					)
					(width 0)
					(fill yes)
				)
			)
		)
	)
	(footprint ""
		(layer "F.Cu")
		(at 79.172816 -181.33568)
		(property "Reference" "C198"
			(at 0 0 0)
			(layer "F.SilkS")
			(hide yes)
			(effects
				(font
					(size 1.27 1.27)
				)
			)
		)
		(property "Value" "SCD1U16V2KX-3GP"
			(at 1.1811 -2.7051 0)
			(unlocked yes)
			(layer "F.Fab")
			(hide yes)
			(effects
				(font
					(size 1.016 1.016)
					(thickness 0.1524)
				)
			)
		)
		(property "Device Type" "C402H22"
			(at 1.1811 -4.2291 0)
			(unlocked yes)
			(layer "F.Fab")
			(hide yes)
			(effects
				(font
					(size 1.016 1.016)
					(thickness 0.1524)
				)
			)
		)
		(duplicate_pad_numbers_are_jumpers no)
		(fp_rect
			(start -0.4318 0.9525)
			(end 0.4318 -0.9525)
			(stroke
				(width 0)
				(type default)
			)
			(fill no)
			(layer "F.CrtYd")
		)
		(fp_rect
			(start -0.4318 0.9525)
			(end 0.4318 -0.9525)
			(stroke
				(width 0)
				(type default)
			)
			(fill no)
			(layer "F.Fab")
		)
		(pad "1" smd custom
			(at 0 -0.4445)
			(size 0.1524 0.1524)
			(layers "F.Cu" "F.Mask" "F.Paste")
			(net "P3V3_STBY")
			(options
				(clearance outline)
				(anchor circle)
			)
			(primitives
				(gr_poly
					(pts
						(arc
							(start 0.3048 -0.2032)
							(mid 0.275042 -0.275042)
							(end 0.2032 -0.3048)
						)
						(arc
							(start -0.2032 -0.3048)
							(mid -0.275042 -0.275042)
							(end -0.3048 -0.2032)
						)
						(arc
							(start -0.3048 0.2032)
							(mid -0.275042 0.275042)
							(end -0.2032 0.3048)
						)
						(arc
							(start 0.2032 0.3048)
							(mid 0.275042 0.275042)
							(end 0.3048 0.2032)
						)
					)
					(width 0)
					(fill yes)
				)
			)
		)
		(pad "2" smd custom
			(at 0 0.4445)
			(size 0.1524 0.1524)
			(layers "F.Cu" "F.Mask" "F.Paste")
			(net "GND")
			(options
				(clearance outline)
				(anchor circle)
			)
			(primitives
				(gr_poly
					(pts
						(arc
							(start 0.3048 -0.2032)
							(mid 0.275042 -0.275042)
							(end 0.2032 -0.3048)
						)
						(arc
							(start -0.2032 -0.3048)
							(mid -0.275042 -0.275042)
							(end -0.3048 -0.2032)
						)
						(arc
							(start -0.3048 0.2032)
							(mid -0.275042 0.275042)
							(end -0.2032 0.3048)
						)
						(arc
							(start 0.2032 0.3048)
							(mid 0.275042 0.275042)
							(end 0.3048 0.2032)
						)
					)
					(width 0)
					(fill yes)
				)
			)
		)
	)
	(footprint ""
		(layer "F.Cu")
		(at 73.561448 -168.460166)
		(property "Reference" "R540"
			(at 0 0 0)
			(layer "F.SilkS")
			(hide yes)
			(effects
				(font
					(size 1.27 1.27)
				)
			)
		)
		(property "Value" "0R2J-2-GP"
			(at 0.064008 -3.993896 0)
			(unlocked yes)
			(layer "F.Fab")
			(hide yes)
			(effects
				(font
					(size 1.016 1.016)
					(thickness 0.1524)
				)
			)
		)
		(property "Device Type" "R402H16"
			(at 0.064008 -5.517896 0)
			(unlocked yes)
			(layer "F.Fab")
			(hide yes)
			(effects
				(font
					(size 1.016 1.016)
					(thickness 0.1524)
				)
			)
		)
		(duplicate_pad_numbers_are_jumpers no)
		(fp_line
			(start -0.508 -0.9398)
			(end -0.508 0.9398)
			(stroke
				(width 0.1524)
				(type default)
			)
			(layer "F.SilkS")
		)
		(fp_line
			(start 0.508 -0.9398)
			(end -0.508 -0.9398)
			(stroke
				(width 0.1524)
				(type default)
			)
			(layer "F.SilkS")
		)
		(fp_rect
			(start -0.508 0.9398)
			(end 0.508 -0.9398)
			(stroke
				(width 0)
				(type default)
			)
			(fill no)
			(layer "F.CrtYd")
		)
		(fp_rect
			(start -0.508 0.9398)
			(end 0.508 -0.9398)
			(stroke
				(width 0)
				(type default)
			)
			(fill no)
			(layer "F.Fab")
		)
		(pad "1" smd custom
			(at 0 -0.4445)
			(size 0.1397 0.1397)
			(layers "F.Cu" "F.Mask" "F.Paste")
			(net "P5V_STBY")
			(options
				(clearance outline)
				(anchor circle)
			)
			(primitives
				(gr_poly
					(pts
						(arc
							(start -0.1778 -0.2794)
							(mid -0.249642 -0.249642)
							(end -0.2794 -0.1778)
						)
						(arc
							(start -0.2794 0.1778)
							(mid -0.249642 0.249642)
							(end -0.1778 0.2794)
						)
						(arc
							(start 0.1778 0.2794)
							(mid 0.249642 0.249642)
							(end 0.2794 0.1778)
						)
						(arc
							(start 0.2794 -0.1778)
							(mid 0.249642 -0.249642)
							(end 0.1778 -0.2794)
						)
					)
					(width 0)
					(fill yes)
				)
			)
		)
		(pad "2" smd custom
			(at 0 0.4445)
			(size 0.1397 0.1397)
			(layers "F.Cu" "F.Mask" "F.Paste")
			(net "TPS74801_P1V15_STBY_BIAS")
			(options
				(clearance outline)
				(anchor circle)
			)
			(primitives
				(gr_poly
					(pts
						(arc
							(start -0.1778 -0.2794)
							(mid -0.249642 -0.249642)
							(end -0.2794 -0.1778)
						)
						(arc
							(start -0.2794 0.1778)
							(mid -0.249642 0.249642)
							(end -0.1778 0.2794)
						)
						(arc
							(start 0.1778 0.2794)
							(mid 0.249642 0.249642)
							(end 0.2794 0.1778)
						)
						(arc
							(start 0.2794 -0.1778)
							(mid 0.249642 -0.249642)
							(end 0.1778 -0.2794)
						)
					)
					(width 0)
					(fill yes)
				)
			)
		)
	)
	(footprint ""
		(layer "F.Cu")
		(at 63.422784 -141.493494 90)
		(property "Reference" "R199"
			(at 0 0 90)
			(layer "F.SilkS")
			(hide yes)
			(effects
				(font
					(size 1.27 1.27)
				)
			)
		)
		(property "Value" "1KR2F-3-GP"
			(at 0.064008 -3.993896 90)
			(unlocked yes)
			(layer "F.Fab")
			(hide yes)
			(effects
				(font
					(size 1.016 1.016)
					(thickness 0.1524)
				)
			)
		)
		(property "Device Type" "R402H16"
			(at 0.064008 -5.517896 90)
			(unlocked yes)
			(layer "F.Fab")
			(hide yes)
			(effects
				(font
					(size 1.016 1.016)
					(thickness 0.1524)
				)
			)
		)
		(duplicate_pad_numbers_are_jumpers no)
		(fp_line
			(start 0.508 -0.9398)
			(end -0.508 -0.9398)
			(stroke
				(width 0.1524)
				(type default)
			)
			(layer "F.SilkS")
		)
		(fp_line
			(start -0.508 -0.9398)
			(end -0.508 0.9398)
			(stroke
				(width 0.1524)
				(type default)
			)
			(layer "F.SilkS")
		)
		(fp_rect
			(start -0.508 0.9398)
			(end 0.508 -0.9398)
			(stroke
				(width 0)
				(type default)
			)
			(fill no)
			(layer "F.CrtYd")
		)
		(fp_rect
			(start -0.508 0.9398)
			(end 0.508 -0.9398)
			(stroke
				(width 0)
				(type default)
			)
			(fill no)
			(layer "F.Fab")
		)
		(pad "1" smd custom
			(at 0 -0.4445 90)
			(size 0.1397 0.1397)
			(layers "F.Cu" "F.Mask" "F.Paste")
			(net "I2C_EXP_RMT_SDA_OUT")
			(options
				(clearance outline)
				(anchor circle)
			)
			(primitives
				(gr_poly
					(pts
						(arc
							(start -0.1778 -0.2794)
							(mid -0.249642 -0.249642)
							(end -0.2794 -0.1778)
						)
						(arc
							(start -0.2794 0.1778)
							(mid -0.249642 0.249642)
							(end -0.1778 0.2794)
						)
						(arc
							(start 0.1778 0.2794)
							(mid 0.249642 0.249642)
							(end 0.2794 0.1778)
						)
						(arc
							(start 0.2794 -0.1778)
							(mid 0.249642 -0.249642)
							(end 0.1778 -0.2794)
						)
					)
					(width 0)
					(fill yes)
				)
			)
		)
		(pad "2" smd custom
			(at 0 0.4445 90)
			(size 0.1397 0.1397)
			(layers "F.Cu" "F.Mask" "F.Paste")
			(net "P3V3_STBY")
			(options
				(clearance outline)
				(anchor circle)
			)
			(primitives
				(gr_poly
					(pts
						(arc
							(start -0.1778 -0.2794)
							(mid -0.249642 -0.249642)
							(end -0.2794 -0.1778)
						)
						(arc
							(start -0.2794 0.1778)
							(mid -0.249642 0.249642)
							(end -0.1778 0.2794)
						)
						(arc
							(start 0.1778 0.2794)
							(mid 0.249642 0.249642)
							(end 0.2794 0.1778)
						)
						(arc
							(start 0.2794 -0.1778)
							(mid 0.249642 -0.249642)
							(end 0.1778 -0.2794)
						)
					)
					(width 0)
					(fill yes)
				)
			)
		)
	)
)
